(kicad_pcb
	(version 20221018)
	(generator pcbnew)
	(general
    (thickness 1.62)
  )
	(paper "A4")
	(title_block
    (title "ECP5 - Datacenter Secure Control Module (DC-SCM)")
    (date "2024-07-01")
    (rev "1.2.1")
		(comment 9 "footprints 206-206 of 506")
	)
	(layers
    (0 "F.Cu" signal)
    (1 "In1.Cu" power)
    (2 "In2.Cu" signal)
    (3 "In3.Cu" power)
    (4 "In4.Cu" power)
    (5 "In5.Cu" signal)
    (6 "In6.Cu" power)
    (31 "B.Cu" signal)
    (32 "B.Adhes" user "B.Adhesive")
    (33 "F.Adhes" user "F.Adhesive")
    (34 "B.Paste" user)
    (35 "F.Paste" user)
    (36 "B.SilkS" user "B.Silkscreen")
    (37 "F.SilkS" user "F.Silkscreen")
    (38 "B.Mask" user)
    (39 "F.Mask" user)
    (40 "Dwgs.User" user "User.Drawings")
    (41 "Cmts.User" user "User.Comments")
    (42 "Eco1.User" user "User.Eco1")
    (43 "Eco2.User" user "User.Eco2")
    (44 "Edge.Cuts" user)
    (45 "Margin" user)
    (46 "B.CrtYd" user "B.Courtyard")
    (47 "F.CrtYd" user "F.Courtyard")
    (48 "B.Fab" user)
    (49 "F.Fab" user)
  )
	(footprint "antmicro-footprints:QFN-56-1EP_8x8mm_P0.5mm" (layer "F.Cu")
    (at 136.75 90.02 -90)
    (descr "QFN 56 Pin")
    (tags "QFN")
    (property "Author" "Antmicro")
    (property "License" "Apache-2.0")
    (property "MPN" "FT4232H-56Q-REEL")
    (property "Manufacturer" "FTDI Chip")
    (property "Sheetfile" "interfaces.kicad_sch")
    (property "Sheetname" "Interfaces")
    (property "ki_description" "Interface Bridges, USB to UART, MPSSE, 1.62 V, 1.98 V, VQFN, 56 Pins, -40 °C")
    (property "ki_keywords" "SMT, INTERFACE, IC, CONTROLLER, USB, UART, I2C, SPI, JTAG")
    (attr smd)
    (fp_text reference "U14" (at 0 -5.32 90) (layer "F.SilkS")
        (effects (font (size 0.7 0.7) (thickness 0.15)))
    )
    (fp_text value "FT4232H_VQFN" (at 0 5.32 90) (layer "F.Fab")
        (effects (font (size 1 1) (thickness 0.15)))
    )
    (fp_text user "${REFERENCE}" (at 0 0 90) (layer "F.Fab")
        (effects (font (size 1 1) (thickness 0.15)))
    )
    (fp_text user "Author: Antmicro" (at -4.4 8.519 -90) (layer "F.Fab") hide
        (effects (font (size 0.7 0.7) (thickness 0.15)) (justify left bottom))
    )
    (fp_text user "License: Apache-2.0" (at -4.4 9.719 -90) (layer "F.Fab") hide
        (effects (font (size 0.7 0.7) (thickness 0.15)) (justify left bottom))
    )
    (fp_line (start -4.111 -3.635) (end -4.111 -4.111)
      (stroke (width 0.15) (type solid)) (layer "F.SilkS"))
    (fp_line (start -4.111 4.11) (end -4.111 3.634)
      (stroke (width 0.15) (type solid)) (layer "F.SilkS"))
    (fp_line (start -3.635 -4.111) (end -4.111 -4.111)
      (stroke (width 0.15) (type solid)) (layer "F.SilkS"))
    (fp_line (start -3.635 4.11) (end -4.111 4.11)
      (stroke (width 0.15) (type solid)) (layer "F.SilkS"))
    (fp_line (start 3.634 -4.111) (end 4.11 -4.111)
      (stroke (width 0.15) (type solid)) (layer "F.SilkS"))
    (fp_line (start 3.634 4.11) (end 4.11 4.11)
      (stroke (width 0.15) (type solid)) (layer "F.SilkS"))
    (fp_line (start 4.11 -4.111) (end 4.11 -3.635)
      (stroke (width 0.15) (type solid)) (layer "F.SilkS"))
    (fp_line (start 4.11 4.11) (end 4.11 3.634)
      (stroke (width 0.15) (type solid)) (layer "F.SilkS"))
    (fp_circle (center -4.35 -3.6) (end -4.3 -3.6)
      (stroke (width 0.15) (type solid)) (fill solid) (layer "F.SilkS"))
    (fp_rect (start 4.4 4.4) (end -4.4 -4.4)
      (stroke (width 0.05) (type solid)) (fill none) (layer "F.CrtYd"))
    (fp_line (start -4 -3) (end -3 -4)
      (stroke (width 0.15) (type solid)) (layer "F.Fab"))
    (fp_rect (start 4 4) (end -4 -4)
      (stroke (width 0.15) (type solid)) (fill none) (layer "F.Fab"))
    (pad "" smd roundrect (at -2.101 -2.101 270) (size 1.13 1.13) (layers "F.Paste") (roundrect_rratio 0.221239))
    (pad "" smd roundrect (at -2.101 -0.7 270) (size 1.13 1.13) (layers "F.Paste") (roundrect_rratio 0.221239))
    (pad "" smd roundrect (at -2.101 0.699 270) (size 1.13 1.13) (layers "F.Paste") (roundrect_rratio 0.221239))
    (pad "" smd roundrect (at -2.101 2.1 270) (size 1.13 1.13) (layers "F.Paste") (roundrect_rratio 0.221239))
    (pad "" smd roundrect (at -0.7 -2.101 270) (size 1.13 1.13) (layers "F.Paste") (roundrect_rratio 0.221239))
    (pad "" smd roundrect (at -0.7 -0.7 270) (size 1.13 1.13) (layers "F.Paste") (roundrect_rratio 0.221239))
    (pad "" smd roundrect (at -0.7 0.699 270) (size 1.13 1.13) (layers "F.Paste") (roundrect_rratio 0.221239))
    (pad "" smd roundrect (at -0.7 2.1 270) (size 1.13 1.13) (layers "F.Paste") (roundrect_rratio 0.221239))
    (pad "" smd roundrect (at 0.699 -2.101 270) (size 1.13 1.13) (layers "F.Paste") (roundrect_rratio 0.221239))
    (pad "" smd roundrect (at 0.699 -0.7 270) (size 1.13 1.13) (layers "F.Paste") (roundrect_rratio 0.221239))
    (pad "" smd roundrect (at 0.699 0.699 270) (size 1.13 1.13) (layers "F.Paste") (roundrect_rratio 0.221239))
    (pad "" smd roundrect (at 0.699 2.1 270) (size 1.13 1.13) (layers "F.Paste") (roundrect_rratio 0.221239))
    (pad "" smd roundrect (at 2.1 -2.101 270) (size 1.13 1.13) (layers "F.Paste") (roundrect_rratio 0.221239))
    (pad "" smd roundrect (at 2.1 -0.7 270) (size 1.13 1.13) (layers "F.Paste") (roundrect_rratio 0.221239))
    (pad "" smd roundrect (at 2.1 0.699 270) (size 1.13 1.13) (layers "F.Paste") (roundrect_rratio 0.221239))
    (pad "" smd roundrect (at 2.1 2.1 270) (size 1.13 1.13) (layers "F.Paste") (roundrect_rratio 0.221239))
    (pad "1" smd roundrect (at -3.938 -3.25 270) (size 0.875 0.3) (layers "F.Cu" "F.Paste" "F.Mask") (roundrect_rratio 0.25)
      (net 510 "unconnected-(U14-EECS-Pad1)") (pinfunction "EECS") (pintype "bidirectional+no_connect"))
    (pad "2" smd roundrect (at -3.938 -2.75 270) (size 0.875 0.3) (layers "F.Cu" "F.Paste" "F.Mask") (roundrect_rratio 0.25)
      (net 657 "VREGOUT") (pinfunction "V_{CORE}") (pintype "power_in"))
    (pad "3" smd roundrect (at -3.938 -2.25 270) (size 0.875 0.3) (layers "F.Cu" "F.Paste" "F.Mask") (roundrect_rratio 0.25)
      (net 511 "/Interfaces/FTDI_CLK") (pinfunction "OSCI") (pintype "input"))
    (pad "4" smd roundrect (at -3.938 -1.75 270) (size 0.875 0.3) (layers "F.Cu" "F.Paste" "F.Mask") (roundrect_rratio 0.25)
      (net 512 "unconnected-(U14-OSCO-Pad4)") (pinfunction "OSCO") (pintype "output+no_connect"))
    (pad "5" smd roundrect (at -3.938 -1.25 270) (size 0.875 0.3) (layers "F.Cu" "F.Paste" "F.Mask") (roundrect_rratio 0.25)
      (net 307 "Net-(U14-V_{PHY})") (pinfunction "V_{PHY}") (pintype "power_in"))
    (pad "6" smd roundrect (at -3.938 -0.75 270) (size 0.875 0.3) (layers "F.Cu" "F.Paste" "F.Mask") (roundrect_rratio 0.25)
      (net 433 "Net-(U14-REF)") (pinfunction "REF") (pintype "input"))
    (pad "7" smd roundrect (at -3.938 -0.25 270) (size 0.875 0.3) (layers "F.Cu" "F.Paste" "F.Mask") (roundrect_rratio 0.25)
      (net 416 "DBG_USB_D_N") (pinfunction "D-") (pintype "bidirectional"))
    (pad "8" smd roundrect (at -3.938 0.249 270) (size 0.875 0.3) (layers "F.Cu" "F.Paste" "F.Mask") (roundrect_rratio 0.25)
      (net 417 "DBG_USB_D_P") (pinfunction "D+") (pintype "bidirectional"))
    (pad "9" smd roundrect (at -3.938 0.749 270) (size 0.875 0.3) (layers "F.Cu" "F.Paste" "F.Mask") (roundrect_rratio 0.25)
      (net 306 "Net-(U14-V_{PLL})") (pinfunction "V_{PLL}") (pintype "power_in"))
    (pad "10" smd roundrect (at -3.938 1.249 270) (size 0.875 0.3) (layers "F.Cu" "F.Paste" "F.Mask") (roundrect_rratio 0.25)
      (net 1 "GND") (pinfunction "TEST") (pintype "input"))
    (pad "11" smd roundrect (at -3.938 1.749 270) (size 0.875 0.3) (layers "F.Cu" "F.Paste" "F.Mask") (roundrect_rratio 0.25)
      (net 432 "Net-(U14-~{RESET})") (pinfunction "~{RESET}") (pintype "input"))
    (pad "12" smd roundrect (at -3.938 2.249 270) (size 0.875 0.3) (layers "F.Cu" "F.Paste" "F.Mask") (roundrect_rratio 0.25)
      (net 21 "JTAG_TCK") (pinfunction "ADBUS0") (pintype "bidirectional"))
    (pad "13" smd roundrect (at -3.938 2.749 270) (size 0.875 0.3) (layers "F.Cu" "F.Paste" "F.Mask") (roundrect_rratio 0.25)
      (net 19 "JTAG_TDI") (pinfunction "ADBUS1") (pintype "bidirectional"))
    (pad "14" smd roundrect (at -3.938 3.249 270) (size 0.875 0.3) (layers "F.Cu" "F.Paste" "F.Mask") (roundrect_rratio 0.25)
      (net 20 "JTAG_TDO") (pinfunction "ADBUS2") (pintype "bidirectional"))
    (pad "15" smd roundrect (at -3.25 3.937) (size 0.875 0.3) (layers "F.Cu" "F.Paste" "F.Mask") (roundrect_rratio 0.25)
      (net 22 "JTAG_TMS") (pinfunction "ADBUS3") (pintype "bidirectional"))
    (pad "16" smd roundrect (at -2.75 3.937) (size 0.875 0.3) (layers "F.Cu" "F.Paste" "F.Mask") (roundrect_rratio 0.25)
      (net 2 "VCC3V3") (pinfunction "V_{CCIO}") (pintype "power_in"))
    (pad "17" smd roundrect (at -2.25 3.937) (size 0.875 0.3) (layers "F.Cu" "F.Paste" "F.Mask") (roundrect_rratio 0.25)
      (net 513 "unconnected-(U14-ADBUS4-Pad17)") (pinfunction "ADBUS4") (pintype "bidirectional+no_connect"))
    (pad "18" smd roundrect (at -1.75 3.937) (size 0.875 0.3) (layers "F.Cu" "F.Paste" "F.Mask") (roundrect_rratio 0.25)
      (net 514 "unconnected-(U14-ADBUS5-Pad18)") (pinfunction "ADBUS5") (pintype "bidirectional+no_connect"))
    (pad "19" smd roundrect (at -1.25 3.937) (size 0.875 0.3) (layers "F.Cu" "F.Paste" "F.Mask") (roundrect_rratio 0.25)
      (net 515 "unconnected-(U14-ADBUS6-Pad19)") (pinfunction "ADBUS6") (pintype "bidirectional+no_connect"))
    (pad "20" smd roundrect (at -0.75 3.937) (size 0.875 0.3) (layers "F.Cu" "F.Paste" "F.Mask") (roundrect_rratio 0.25)
      (net 516 "unconnected-(U14-ADBUS7-Pad20)") (pinfunction "ADBUS7") (pintype "bidirectional+no_connect"))
    (pad "21" smd roundrect (at -0.25 3.937) (size 0.875 0.3) (layers "F.Cu" "F.Paste" "F.Mask") (roundrect_rratio 0.25)
      (net 1 "GND") (pinfunction "GND") (pintype "power_in"))
    (pad "22" smd roundrect (at 0.249 3.937) (size 0.875 0.3) (layers "F.Cu" "F.Paste" "F.Mask") (roundrect_rratio 0.25)
      (net 517 "unconnected-(U14-BDBUS0-Pad22)") (pinfunction "BDBUS0") (pintype "bidirectional+no_connect"))
    (pad "23" smd roundrect (at 0.749 3.937) (size 0.875 0.3) (layers "F.Cu" "F.Paste" "F.Mask") (roundrect_rratio 0.25)
      (net 518 "unconnected-(U14-BDBUS1-Pad23)") (pinfunction "BDBUS1") (pintype "bidirectional+no_connect"))
    (pad "24" smd roundrect (at 1.249 3.937) (size 0.875 0.3) (layers "F.Cu" "F.Paste" "F.Mask") (roundrect_rratio 0.25)
      (net 519 "unconnected-(U14-BDBUS2-Pad24)") (pinfunction "BDBUS2") (pintype "bidirectional+no_connect"))
    (pad "25" smd roundrect (at 1.749 3.937) (size 0.875 0.3) (layers "F.Cu" "F.Paste" "F.Mask") (roundrect_rratio 0.25)
      (net 520 "unconnected-(U14-BDBUS3-Pad25)") (pinfunction "BDBUS3") (pintype "bidirectional+no_connect"))
    (pad "26" smd roundrect (at 2.249 3.937) (size 0.875 0.3) (layers "F.Cu" "F.Paste" "F.Mask") (roundrect_rratio 0.25)
      (net 521 "unconnected-(U14-BDBUS4-Pad26)") (pinfunction "BDBUS4") (pintype "bidirectional+no_connect"))
    (pad "27" smd roundrect (at 2.749 3.937) (size 0.875 0.3) (layers "F.Cu" "F.Paste" "F.Mask") (roundrect_rratio 0.25)
      (net 522 "unconnected-(U14-BDBUS5-Pad27)") (pinfunction "BDBUS5") (pintype "bidirectional+no_connect"))
    (pad "28" smd roundrect (at 3.249 3.937) (size 0.875 0.3) (layers "F.Cu" "F.Paste" "F.Mask") (roundrect_rratio 0.25)
      (net 523 "unconnected-(U14-BDBUS6-Pad28)") (pinfunction "BDBUS6") (pintype "bidirectional+no_connect"))
    (pad "29" smd roundrect (at 3.937 3.249 270) (size 0.875 0.3) (layers "F.Cu" "F.Paste" "F.Mask") (roundrect_rratio 0.25)
      (net 524 "unconnected-(U14-BDBUS7-Pad29)") (pinfunction "BDBUS7") (pintype "bidirectional+no_connect"))
    (pad "30" smd roundrect (at 3.937 2.749 270) (size 0.875 0.3) (layers "F.Cu" "F.Paste" "F.Mask") (roundrect_rratio 0.25)
      (net 436 "Net-(U14-~{SUSPEND})") (pinfunction "~{SUSPEND}") (pintype "output"))
    (pad "31" smd roundrect (at 3.937 2.249 270) (size 0.875 0.3) (layers "F.Cu" "F.Paste" "F.Mask") (roundrect_rratio 0.25)
      (net 657 "VREGOUT") (pinfunction "V_{CORE}") (pintype "passive"))
    (pad "32" smd roundrect (at 3.937 1.749 270) (size 0.875 0.3) (layers "F.Cu" "F.Paste" "F.Mask") (roundrect_rratio 0.25)
      (net 525 "unconnected-(U14-CDBUS0-Pad32)") (pinfunction "CDBUS0") (pintype "bidirectional+no_connect"))
    (pad "33" smd roundrect (at 3.937 1.249 270) (size 0.875 0.3) (layers "F.Cu" "F.Paste" "F.Mask") (roundrect_rratio 0.25)
      (net 526 "unconnected-(U14-CDBUS1-Pad33)") (pinfunction "CDBUS1") (pintype "bidirectional+no_connect"))
    (pad "34" smd roundrect (at 3.937 0.749 270) (size 0.875 0.3) (layers "F.Cu" "F.Paste" "F.Mask") (roundrect_rratio 0.25)
      (net 527 "unconnected-(U14-CDBUS2-Pad34)") (pinfunction "CDBUS2") (pintype "bidirectional+no_connect"))
    (pad "35" smd roundrect (at 3.937 0.249 270) (size 0.875 0.3) (layers "F.Cu" "F.Paste" "F.Mask") (roundrect_rratio 0.25)
      (net 528 "unconnected-(U14-CDBUS3-Pad35)") (pinfunction "CDBUS3") (pintype "bidirectional+no_connect"))
    (pad "36" smd roundrect (at 3.937 -0.25 270) (size 0.875 0.3) (layers "F.Cu" "F.Paste" "F.Mask") (roundrect_rratio 0.25)
      (net 2 "VCC3V3") (pinfunction "V_{CCIO}") (pintype "passive"))
    (pad "37" smd roundrect (at 3.937 -0.75 270) (size 0.875 0.3) (layers "F.Cu" "F.Paste" "F.Mask") (roundrect_rratio 0.25)
      (net 529 "unconnected-(U14-CDBUS4-Pad37)") (pinfunction "CDBUS4") (pintype "bidirectional+no_connect"))
    (pad "38" smd roundrect (at 3.937 -1.25 270) (size 0.875 0.3) (layers "F.Cu" "F.Paste" "F.Mask") (roundrect_rratio 0.25)
      (net 530 "unconnected-(U14-CDBUS5-Pad38)") (pinfunction "CDBUS5") (pintype "bidirectional+no_connect"))
    (pad "39" smd roundrect (at 3.937 -1.75 270) (size 0.875 0.3) (layers "F.Cu" "F.Paste" "F.Mask") (roundrect_rratio 0.25)
      (net 531 "unconnected-(U14-CDBUS6-Pad39)") (pinfunction "CDBUS6") (pintype "bidirectional+no_connect"))
    (pad "40" smd roundrect (at 3.937 -2.25 270) (size 0.875 0.3) (layers "F.Cu" "F.Paste" "F.Mask") (roundrect_rratio 0.25)
      (net 532 "unconnected-(U14-CDBUS7-Pad40)") (pinfunction "CDBUS7") (pintype "bidirectional+no_connect"))
    (pad "41" smd roundrect (at 3.937 -2.75 270) (size 0.875 0.3) (layers "F.Cu" "F.Paste" "F.Mask") (roundrect_rratio 0.25)
      (net 1 "GND") (pinfunction "GND") (pintype "passive"))
    (pad "42" smd roundrect (at 3.937 -3.25 270) (size 0.875 0.3) (layers "F.Cu" "F.Paste" "F.Mask") (roundrect_rratio 0.25)
      (net 533 "unconnected-(U14-DDBUS0-Pad42)") (pinfunction "DDBUS0") (pintype "bidirectional+no_connect"))
    (pad "43" smd roundrect (at 3.249 -3.938) (size 0.875 0.3) (layers "F.Cu" "F.Paste" "F.Mask") (roundrect_rratio 0.25)
      (net 657 "VREGOUT") (pinfunction "V_{REGOUT}") (pintype "power_out"))
    (pad "44" smd roundrect (at 2.749 -3.938) (size 0.875 0.3) (layers "F.Cu" "F.Paste" "F.Mask") (roundrect_rratio 0.25)
      (net 2 "VCC3V3") (pinfunction "V_{REGIN}") (pintype "power_in"))
    (pad "45" smd roundrect (at 2.249 -3.938) (size 0.875 0.3) (layers "F.Cu" "F.Paste" "F.Mask") (roundrect_rratio 0.25)
      (net 1 "GND") (pinfunction "GND") (pintype "passive"))
    (pad "46" smd roundrect (at 1.749 -3.938) (size 0.875 0.3) (layers "F.Cu" "F.Paste" "F.Mask") (roundrect_rratio 0.25)
      (net 534 "unconnected-(U14-DDBUS1-Pad46)") (pinfunction "DDBUS1") (pintype "bidirectional+no_connect"))
    (pad "47" smd roundrect (at 1.249 -3.938) (size 0.875 0.3) (layers "F.Cu" "F.Paste" "F.Mask") (roundrect_rratio 0.25)
      (net 535 "unconnected-(U14-DDBUS2-Pad47)") (pinfunction "DDBUS2") (pintype "bidirectional+no_connect"))
    (pad "48" smd roundrect (at 0.749 -3.938) (size 0.875 0.3) (layers "F.Cu" "F.Paste" "F.Mask") (roundrect_rratio 0.25)
      (net 536 "unconnected-(U14-DDBUS3-Pad48)") (pinfunction "DDBUS3") (pintype "bidirectional+no_connect"))
    (pad "49" smd roundrect (at 0.249 -3.938) (size 0.875 0.3) (layers "F.Cu" "F.Paste" "F.Mask") (roundrect_rratio 0.25)
      (net 537 "unconnected-(U14-DDBUS4-Pad49)") (pinfunction "DDBUS4") (pintype "bidirectional+no_connect"))
    (pad "50" smd roundrect (at -0.25 -3.938) (size 0.875 0.3) (layers "F.Cu" "F.Paste" "F.Mask") (roundrect_rratio 0.25)
      (net 2 "VCC3V3") (pinfunction "V_{CCIO}") (pintype "passive"))
    (pad "51" smd roundrect (at -0.75 -3.938) (size 0.875 0.3) (layers "F.Cu" "F.Paste" "F.Mask") (roundrect_rratio 0.25)
      (net 538 "unconnected-(U14-DDBUS5-Pad51)") (pinfunction "DDBUS5") (pintype "bidirectional+no_connect"))
    (pad "52" smd roundrect (at -1.25 -3.938) (size 0.875 0.3) (layers "F.Cu" "F.Paste" "F.Mask") (roundrect_rratio 0.25)
      (net 539 "unconnected-(U14-DDBUS6-Pad52)") (pinfunction "DDBUS6") (pintype "bidirectional+no_connect"))
    (pad "53" smd roundrect (at -1.75 -3.938) (size 0.875 0.3) (layers "F.Cu" "F.Paste" "F.Mask") (roundrect_rratio 0.25)
      (net 434 "Net-(U14-DDBUS7)") (pinfunction "DDBUS7") (pintype "bidirectional"))
    (pad "54" smd roundrect (at -2.25 -3.938) (size 0.875 0.3) (layers "F.Cu" "F.Paste" "F.Mask") (roundrect_rratio 0.25)
      (net 435 "Net-(U14-~{PWR_{EN}})") (pinfunction "~{PWR_{EN}}") (pintype "output"))
    (pad "55" smd roundrect (at -2.75 -3.938) (size 0.875 0.3) (layers "F.Cu" "F.Paste" "F.Mask") (roundrect_rratio 0.25)
      (net 540 "unconnected-(U14-EEDATA-Pad55)") (pinfunction "EEDATA") (pintype "bidirectional+no_connect"))
    (pad "56" smd roundrect (at -3.25 -3.938) (size 0.875 0.3) (layers "F.Cu" "F.Paste" "F.Mask") (roundrect_rratio 0.25)
      (net 541 "unconnected-(U14-EECLK-Pad56)") (pinfunction "EECLK") (pintype "output+no_connect"))
    (pad "57" smd rect (at 0 0 270) (size 5.9 5.9) (layers "F.Cu" "F.Mask")
      (net 1 "GND") (pinfunction "GND") (pintype "passive"))
  )
)
